# T6G (Grand Teton) — schematic netlist excerpt (pin names and nets, part order shuffled) for the footprints in the layout excerpt that follows; sources: Cadence DE-HDL packaged netlist, KiCad conversion of 04192023_DAF0TMB3IC0_F0TG_MB_C_brd_V02_OCP.brd

R6101  Q_RES  0 5% CHIP  pkg 0402LF  page 171 : A = SCM_JTAG_MUX_S0 ; B = SCM_JTAG_MUX_S0_R1
R3685  Q_RES  0 5% EMPTY  pkg 0402LF  page 257 : A = P5V_ADC ; B = P5V_ADC_MAM

(kicad_pcb
	(version 20260206)
	(generator "pcbnew")
	(generator_version "10.0")
	(general
		(thickness 1.6)
		(legacy_teardrops no)
	)
	(paper "A4")
	(title_block
		(title "04192023_DAF0TMB3IC0_F0TG_MB_C_brd_V02_OCP.brd")
		(comment 1 "Grand Teton / footprints 3851-3852 of 8354")
	)
	(layers
		(0 "F.Cu" signal "TOP")
		(4 "In1.Cu" signal "GND")
		(6 "In2.Cu" signal "IN1")
		(8 "In3.Cu" signal "GND1")
		(10 "In4.Cu" signal "IN2")
		(12 "In5.Cu" signal "GND2")
		(14 "In6.Cu" signal "IN3")
		(16 "In7.Cu" signal "GND3")
		(18 "In8.Cu" signal "VCC")
		(20 "In9.Cu" signal "VCC1")
		(22 "In10.Cu" signal "GND4")
		(24 "In11.Cu" signal "IN4")
		(26 "In12.Cu" signal "GND5")
		(28 "In13.Cu" signal "IN5")
		(30 "In14.Cu" signal "GND6")
		(32 "In15.Cu" signal "IN6")
		(34 "In16.Cu" signal "GND7")
		(2 "B.Cu" signal "BOTTOM")
		(9 "F.Adhes" user "F.Adhesive")
		(11 "B.Adhes" user "B.Adhesive")
		(13 "F.Paste" user "Package Geometry/Pastemask Top")
		(15 "B.Paste" user "Package Geometry/Pastemask Bottom")
		(5 "F.SilkS" user "Ref Des/Silkscreen Top")
		(7 "B.SilkS" user "Ref Des/Silkscreen Bottom")
		(1 "F.Mask" user "Board Geometry/Soldermask Top")
		(3 "B.Mask" user "Board Geometry/Soldermask Bottom")
		(17 "Dwgs.User" user "User.Drawings")
		(19 "Cmts.User" user "User.Comments")
		(21 "Eco1.User" user "User.Eco1")
		(23 "Eco2.User" user "User.Eco2")
		(25 "Edge.Cuts" user "Board Geometry/Outline")
		(27 "Margin" user)
		(31 "F.CrtYd" user "Package Geometry/Place Bound Top")
		(29 "B.CrtYd" user "Package Geometry/Place Bound Bottom")
		(35 "F.Fab" user "Ref Des/Assembly Top")
		(33 "B.Fab" user "Ref Des/Assembly Bottom")
	)
	(footprint ""
		(layer "F.Cu")
		(at 323.637148 -43.573954)
		(property "Reference" "R3685"
			(at 0 0 0)
			(layer "F.SilkS")
			(hide yes)
			(effects
				(font
					(size 1.27 1.27)
				)
			)
		)
		(property "Value" ""
			(at 0 0 0)
			(layer "F.Fab")
			(effects
				(font
					(size 1.27 1.27)
				)
			)
		)
		(duplicate_pad_numbers_are_jumpers no)
		(fp_line
			(start -0.7874 -0.4064)
			(end 0.7874 -0.4064)
			(stroke
				(width 0.1524)
				(type default)
			)
			(layer "F.SilkS")
		)
		(fp_line
			(start -0.7874 0.4064)
			(end -0.7874 -0.4064)
			(stroke
				(width 0.1524)
				(type default)
			)
			(layer "F.SilkS")
		)
		(fp_line
			(start 0.7874 -0.4064)
			(end 0.7874 0.4064)
			(stroke
				(width 0.1524)
				(type default)
			)
			(layer "F.SilkS")
		)
		(fp_line
			(start 0.7874 0.4064)
			(end -0.7874 0.4064)
			(stroke
				(width 0.1524)
				(type default)
			)
			(layer "F.SilkS")
		)
		(fp_line
			(start -0.67945 -0.305054)
			(end -0.12065 -0.305054)
			(stroke
				(width 0.1)
				(type default)
			)
			(layer "F.Fab")
		)
		(fp_line
			(start -0.67945 0.3048)
			(end -0.67945 -0.305054)
			(stroke
				(width 0.1)
				(type default)
			)
			(layer "F.Fab")
		)
		(fp_line
			(start -0.12065 -0.305054)
			(end -0.12065 -0.2794)
			(stroke
				(width 0.1)
				(type default)
			)
			(layer "F.Fab")
		)
		(fp_line
			(start -0.12065 -0.2794)
			(end 0.12065 -0.2794)
			(stroke
				(width 0.1)
				(type default)
			)
			(layer "F.Fab")
		)
		(fp_line
			(start -0.12065 0.2794)
			(end -0.12065 0.3048)
			(stroke
				(width 0.1)
				(type default)
			)
			(layer "F.Fab")
		)
		(fp_line
			(start -0.12065 0.3048)
			(end -0.67945 0.3048)
			(stroke
				(width 0.1)
				(type default)
			)
			(layer "F.Fab")
		)
		(fp_line
			(start 0.120396 0.2794)
			(end -0.12065 0.2794)
			(stroke
				(width 0.1)
				(type default)
			)
			(layer "F.Fab")
		)
		(fp_line
			(start 0.120396 0.3048)
			(end 0.120396 0.2794)
			(stroke
				(width 0.1)
				(type default)
			)
			(layer "F.Fab")
		)
		(fp_line
			(start 0.12065 -0.3048)
			(end 0.67945 -0.3048)
			(stroke
				(width 0.1)
				(type default)
			)
			(layer "F.Fab")
		)
		(fp_line
			(start 0.12065 -0.2794)
			(end 0.12065 -0.3048)
			(stroke
				(width 0.1)
				(type default)
			)
			(layer "F.Fab")
		)
		(fp_line
			(start 0.67945 -0.3048)
			(end 0.67945 0.3048)
			(stroke
				(width 0.1)
				(type default)
			)
			(layer "F.Fab")
		)
		(fp_line
			(start 0.67945 0.3048)
			(end 0.120396 0.3048)
			(stroke
				(width 0.1)
				(type default)
			)
			(layer "F.Fab")
		)
		(pad "1" smd rect
			(at -0.40005 0 180)
			(size 0.4572 0.508)
			(layers "F.Cu" "F.Mask" "F.Paste")
			(net "P5V_ADC")
		)
		(pad "2" smd rect
			(at 0.40005 0 180)
			(size 0.4572 0.508)
			(layers "F.Cu" "F.Mask" "F.Paste")
			(net "P5V_ADC_MAM")
		)
	)
	(footprint ""
		(layer "F.Cu")
		(at 118.718584 -56.582056 180)
		(property "Reference" "R6101"
			(at 0 0 180)
			(layer "F.SilkS")
			(hide yes)
			(effects
				(font
					(size 1.27 1.27)
				)
			)
		)
		(property "Value" ""
			(at 0 0 180)
			(layer "F.Fab")
			(effects
				(font
					(size 1.27 1.27)
				)
			)
		)
		(duplicate_pad_numbers_are_jumpers no)
		(fp_line
			(start 0.7874 0.4064)
			(end -0.7874 0.4064)
			(stroke
				(width 0.1524)
				(type default)
			)
			(layer "F.SilkS")
		)
		(fp_line
			(start 0.7874 -0.4064)
			(end 0.7874 0.4064)
			(stroke
				(width 0.1524)
				(type default)
			)
			(layer "F.SilkS")
		)
		(fp_line
			(start -0.7874 0.4064)
			(end -0.7874 -0.4064)
			(stroke
				(width 0.1524)
				(type default)
			)
			(layer "F.SilkS")
		)
		(fp_line
			(start -0.7874 -0.4064)
			(end 0.7874 -0.4064)
			(stroke
				(width 0.1524)
				(type default)
			)
			(layer "F.SilkS")
		)
		(fp_line
			(start 0.67945 0.3048)
			(end 0.120396 0.3048)
			(stroke
				(width 0.1)
				(type default)
			)
			(layer "F.Fab")
		)
		(fp_line
			(start 0.67945 -0.3048)
			(end 0.67945 0.3048)
			(stroke
				(width 0.1)
				(type default)
			)
			(layer "F.Fab")
		)
		(fp_line
			(start 0.12065 -0.2794)
			(end 0.12065 -0.3048)
			(stroke
				(width 0.1)
				(type default)
			)
			(layer "F.Fab")
		)
		(fp_line
			(start 0.12065 -0.3048)
			(end 0.67945 -0.3048)
			(stroke
				(width 0.1)
				(type default)
			)
			(layer "F.Fab")
		)
		(fp_line
			(start 0.120396 0.3048)
			(end 0.120396 0.2794)
			(stroke
				(width 0.1)
				(type default)
			)
			(layer "F.Fab")
		)
		(fp_line
			(start 0.120396 0.2794)
			(end -0.12065 0.2794)
			(stroke
				(width 0.1)
				(type default)
			)
			(layer "F.Fab")
		)
		(fp_line
			(start -0.12065 0.3048)
			(end -0.67945 0.3048)
			(stroke
				(width 0.1)
				(type default)
			)
			(layer "F.Fab")
		)
		(fp_line
			(start -0.12065 0.2794)
			(end -0.12065 0.3048)
			(stroke
				(width 0.1)
				(type default)
			)
			(layer "F.Fab")
		)
		(fp_line
			(start -0.12065 -0.2794)
			(end 0.12065 -0.2794)
			(stroke
				(width 0.1)
				(type default)
			)
			(layer "F.Fab")
		)
		(fp_line
			(start -0.12065 -0.305054)
			(end -0.12065 -0.2794)
			(stroke
				(width 0.1)
				(type default)
			)
			(layer "F.Fab")
		)
		(fp_line
			(start -0.67945 0.3048)
			(end -0.67945 -0.305054)
			(stroke
				(width 0.1)
				(type default)
			)
			(layer "F.Fab")
		)
		(fp_line
			(start -0.67945 -0.305054)
			(end -0.12065 -0.305054)
			(stroke
				(width 0.1)
				(type default)
			)
			(layer "F.Fab")
		)
		(pad "1" smd circle
			(at -0.40005 0 180)
			(size 0 0)
			(layers "F.Cu" "F.Mask" "F.Paste")
			(net "SCM_JTAG_MUX_S0")
		)
		(pad "2" smd circle
			(at 0.40005 0 180)
			(size 0 0)
			(layers "F.Cu" "F.Mask" "F.Paste")
			(net "SCM_JTAG_MUX_S0_R1")
		)
	)
)
